# BASEBOARD_FAB2 (Tioga Pass) — schematic netlist excerpt (pin names and nets, part order shuffled) for the footprints in the layout excerpt that follows; sources: Cadence DE-HDL packaged netlist, KiCad conversion of Wiwynn_Tioga_Pass_MB.brd

R1U55  RES  0.0 5% EMPTY  pkg 0402  page 152 : A = H_CPU1_MEMGHJ_MEMHOT_G_N ; B = H_CPU1_MEMGHJ_MEMHOT_G_PCH_N
R25W141  RES  0.0 5% CHIP  pkg 0402  page 145 : A = RST_PLTRST_BUF_N ; B = RST_PLTRST_BUF_N_R
R4D4  RES  27.4 1% CHIP  pkg 0402  page 103 : A = CLK_100M_CPU1_BCLK0_R_DP ; B = CLK_100M_CPU1_BCLK0_DP

(kicad_pcb
	(version 20260206)
	(generator "pcbnew")
	(generator_version "10.0")
	(general
		(thickness 1.6)
		(legacy_teardrops no)
	)
	(paper "A4")
	(title_block
		(title "Wiwynn_Tioga_Pass_MB.brd")
		(comment 1 "Tioga Pass / footprints 403-405 of 4770")
	)
	(layers
		(0 "F.Cu" signal "TOP")
		(4 "In1.Cu" signal "L2GND")
		(6 "In2.Cu" signal "L3")
		(8 "In3.Cu" signal "L4GND")
		(10 "In4.Cu" signal "L5")
		(12 "In5.Cu" signal "L6GND")
		(14 "In6.Cu" signal "L7VCC")
		(16 "In7.Cu" signal "L8VCC")
		(18 "In8.Cu" signal "L9GND")
		(20 "In9.Cu" signal "L10")
		(22 "In10.Cu" signal "L11GND")
		(24 "In11.Cu" signal "L12")
		(26 "In12.Cu" signal "L13GND")
		(2 "B.Cu" signal "BOTTOM")
		(9 "F.Adhes" user "F.Adhesive")
		(11 "B.Adhes" user "B.Adhesive")
		(13 "F.Paste" user "Package Geometry/Pastemask Top")
		(15 "B.Paste" user "Package Geometry/Pastemask Bottom")
		(5 "F.SilkS" user "Ref Des/Silkscreen Top")
		(7 "B.SilkS" user "Ref Des/Silkscreen Bottom")
		(1 "F.Mask" user "Board Geometry/Soldermask Top")
		(3 "B.Mask" user "Board Geometry/Soldermask Bottom")
		(17 "Dwgs.User" user "User.Drawings")
		(19 "Cmts.User" user "User.Comments")
		(21 "Eco1.User" user "User.Eco1")
		(23 "Eco2.User" user "User.Eco2")
		(25 "Edge.Cuts" user "Board Geometry/Outline")
		(27 "Margin" user)
		(31 "F.CrtYd" user "Package Geometry/Place Bound Top")
		(29 "B.CrtYd" user "Package Geometry/Place Bound Bottom")
		(35 "F.Fab" user "Ref Des/Assembly Top")
		(33 "B.Fab" user "Ref Des/Assembly Bottom")
	)
	(footprint ""
		(layer "F.Cu")
		(at 168.656 -86.868 180)
		(property "Reference" "R4D4"
			(at 0 0 180)
			(layer "F.SilkS")
			(hide yes)
			(effects
				(font
					(size 1.27 1.27)
				)
			)
		)
		(property "Value" ""
			(at 0 0 180)
			(layer "F.Fab")
			(effects
				(font
					(size 1.27 1.27)
				)
			)
		)
		(duplicate_pad_numbers_are_jumpers no)
		(fp_poly
			(pts
				(xy -0.2794 -0.1016) (xy 0.2794 -0.1016) (xy 0.2794 0.9906) (xy -0.2794 0.9906)
			)
			(stroke
				(width 0)
				(type default)
			)
			(fill no)
			(layer "F.CrtYd")
		)
		(fp_line
			(start 0.2794 0.9906)
			(end 0.2794 -0.1016)
			(stroke
				(width 0.1)
				(type default)
			)
			(layer "F.Fab")
		)
		(fp_line
			(start 0.2794 -0.1016)
			(end -0.2794 -0.1016)
			(stroke
				(width 0.1)
				(type default)
			)
			(layer "F.Fab")
		)
		(fp_line
			(start -0.2794 0.9906)
			(end 0.2794 0.9906)
			(stroke
				(width 0.1)
				(type default)
			)
			(layer "F.Fab")
		)
		(fp_line
			(start -0.2794 -0.1016)
			(end -0.2794 0.9906)
			(stroke
				(width 0.1)
				(type default)
			)
			(layer "F.Fab")
		)
		(pad "1" smd rect
			(at 0 0 180)
			(size 0.508 0.508)
			(layers "F.Cu" "F.Mask" "F.Paste")
			(net "CLK_100M_CPU1_BCLK0_R_DP")
		)
		(pad "2" smd rect
			(at 0 0.889 180)
			(size 0.508 0.508)
			(layers "F.Cu" "F.Mask" "F.Paste")
			(net "CLK_100M_CPU1_BCLK0_DP")
		)
		(zone
			(layer "F.Cu")
			(hatch none 0.5)
			(connect_pads
				(clearance 0)
			)
			(min_thickness 0.25)
			(keepout
				(tracks not_allowed)
				(vias allowed)
				(pads allowed)
				(copperpour not_allowed)
				(footprints allowed)
			)
			(placement
				(enabled no)
				(sheetname "")
			)
			(fill
				(thermal_gap 0.5)
				(thermal_bridge_width 0.5)
				(island_removal_mode 0)
			)
			(polygon
				(pts
					(xy 168.91 -87.503) (xy 168.402 -87.503) (xy 168.402 -87.122) (xy 168.91 -87.122)
				)
			)
		)
		(zone
			(layer "F.Cu")
			(hatch none 0.5)
			(connect_pads
				(clearance 0)
			)
			(min_thickness 0.25)
			(keepout
				(tracks allowed)
				(vias not_allowed)
				(pads allowed)
				(copperpour not_allowed)
				(footprints allowed)
			)
			(placement
				(enabled no)
				(sheetname "")
			)
			(fill
				(thermal_gap 0.5)
				(thermal_bridge_width 0.5)
				(island_removal_mode 0)
			)
			(polygon
				(pts
					(xy 168.91 -87.122) (xy 168.402 -87.122) (xy 168.402 -87.503) (xy 168.91 -87.503)
				)
			)
		)
	)
	(footprint ""
		(layer "F.Cu")
		(at 437.7055 -14.605 -90)
		(property "Reference" "R1U55"
			(at 0 0 270)
			(layer "F.SilkS")
			(hide yes)
			(effects
				(font
					(size 1.27 1.27)
				)
			)
		)
		(property "Value" ""
			(at 0 0 270)
			(layer "F.Fab")
			(effects
				(font
					(size 1.27 1.27)
				)
			)
		)
		(duplicate_pad_numbers_are_jumpers no)
		(fp_poly
			(pts
				(xy -0.2794 -0.1016) (xy 0.2794 -0.1016) (xy 0.2794 0.9906) (xy -0.2794 0.9906)
			)
			(stroke
				(width 0)
				(type default)
			)
			(fill no)
			(layer "F.CrtYd")
		)
		(fp_line
			(start -0.2794 0.9906)
			(end 0.2794 0.9906)
			(stroke
				(width 0.1)
				(type default)
			)
			(layer "F.Fab")
		)
		(fp_line
			(start 0.2794 0.9906)
			(end 0.2794 -0.1016)
			(stroke
				(width 0.1)
				(type default)
			)
			(layer "F.Fab")
		)
		(fp_line
			(start -0.2794 -0.1016)
			(end -0.2794 0.9906)
			(stroke
				(width 0.1)
				(type default)
			)
			(layer "F.Fab")
		)
		(fp_line
			(start 0.2794 -0.1016)
			(end -0.2794 -0.1016)
			(stroke
				(width 0.1)
				(type default)
			)
			(layer "F.Fab")
		)
		(pad "1" smd rect
			(at 0 0 270)
			(size 0.508 0.508)
			(layers "F.Cu" "F.Mask" "F.Paste")
			(net "H_CPU1_MEMGHJ_MEMHOT_G_N")
		)
		(pad "2" smd rect
			(at 0 0.889 270)
			(size 0.508 0.508)
			(layers "F.Cu" "F.Mask" "F.Paste")
			(net "H_CPU1_MEMGHJ_MEMHOT_G_PCH_N")
		)
		(zone
			(layer "F.Cu")
			(hatch none 0.5)
			(connect_pads
				(clearance 0)
			)
			(min_thickness 0.25)
			(keepout
				(tracks not_allowed)
				(vias allowed)
				(pads allowed)
				(copperpour not_allowed)
				(footprints allowed)
			)
			(placement
				(enabled no)
				(sheetname "")
			)
			(fill
				(thermal_gap 0.5)
				(thermal_bridge_width 0.5)
				(island_removal_mode 0)
			)
			(polygon
				(pts
					(xy 437.0705 -14.859) (xy 437.0705 -14.351) (xy 437.4515 -14.351) (xy 437.4515 -14.859)
				)
			)
		)
		(zone
			(layer "F.Cu")
			(hatch none 0.5)
			(connect_pads
				(clearance 0)
			)
			(min_thickness 0.25)
			(keepout
				(tracks allowed)
				(vias not_allowed)
				(pads allowed)
				(copperpour not_allowed)
				(footprints allowed)
			)
			(placement
				(enabled no)
				(sheetname "")
			)
			(fill
				(thermal_gap 0.5)
				(thermal_bridge_width 0.5)
				(island_removal_mode 0)
			)
			(polygon
				(pts
					(xy 437.4515 -14.859) (xy 437.4515 -14.351) (xy 437.0705 -14.351) (xy 437.0705 -14.859)
				)
			)
		)
	)
	(footprint ""
		(layer "F.Cu")
		(at 412.742888 -48.071024 180)
		(property "Reference" "R25W141"
			(at -0.8382 -0.67818 180)
			(unlocked yes)
			(layer "F.SilkS")
			(effects
				(font
					(size 0.4064 0.254)
					(thickness 0.1524)
				)
				(justify left)
			)
		)
		(property "Value" ""
			(at 0 0 180)
			(layer "F.Fab")
			(effects
				(font
					(size 1.27 1.27)
				)
			)
		)
		(duplicate_pad_numbers_are_jumpers no)
		(fp_poly
			(pts
				(xy -0.2794 -0.1016) (xy 0.2794 -0.1016) (xy 0.2794 0.9906) (xy -0.2794 0.9906)
			)
			(stroke
				(width 0)
				(type default)
			)
			(fill no)
			(layer "F.CrtYd")
		)
		(fp_line
			(start 0.2794 0.9906)
			(end 0.2794 -0.1016)
			(stroke
				(width 0.1)
				(type default)
			)
			(layer "F.Fab")
		)
		(fp_line
			(start 0.2794 -0.1016)
			(end -0.2794 -0.1016)
			(stroke
				(width 0.1)
				(type default)
			)
			(layer "F.Fab")
		)
		(fp_line
			(start -0.2794 0.9906)
			(end 0.2794 0.9906)
			(stroke
				(width 0.1)
				(type default)
			)
			(layer "F.Fab")
		)
		(fp_line
			(start -0.2794 -0.1016)
			(end -0.2794 0.9906)
			(stroke
				(width 0.1)
				(type default)
			)
			(layer "F.Fab")
		)
		(pad "1" smd rect
			(at 0 0 180)
			(size 0.508 0.508)
			(layers "F.Cu" "F.Mask" "F.Paste")
			(net "RST_PLTRST_BUF_N")
		)
		(pad "2" smd rect
			(at 0 0.889 180)
			(size 0.508 0.508)
			(layers "F.Cu" "F.Mask" "F.Paste")
			(net "RST_PLTRST_BUF_N_R")
		)
		(zone
			(layer "F.Cu")
			(hatch none 0.5)
			(connect_pads
				(clearance 0)
			)
			(min_thickness 0.25)
			(keepout
				(tracks not_allowed)
				(vias allowed)
				(pads allowed)
				(copperpour not_allowed)
				(footprints allowed)
			)
			(placement
				(enabled no)
				(sheetname "")
			)
			(fill
				(thermal_gap 0.5)
				(thermal_bridge_width 0.5)
				(island_removal_mode 0)
			)
			(polygon
				(pts
					(xy 412.996888 -48.706024) (xy 412.488888 -48.706024) (xy 412.488888 -48.325024) (xy 412.996888 -48.325024)
				)
			)
		)
		(zone
			(layer "F.Cu")
			(hatch none 0.5)
			(connect_pads
				(clearance 0)
			)
			(min_thickness 0.25)
			(keepout
				(tracks allowed)
				(vias not_allowed)
				(pads allowed)
				(copperpour not_allowed)
				(footprints allowed)
			)
			(placement
				(enabled no)
				(sheetname "")
			)
			(fill
				(thermal_gap 0.5)
				(thermal_bridge_width 0.5)
				(island_removal_mode 0)
			)
			(polygon
				(pts
					(xy 412.996888 -48.325024) (xy 412.488888 -48.325024) (xy 412.488888 -48.706024) (xy 412.996888 -48.706024)
				)
			)
		)
	)
)
